(kicad_pcb
	(version 20260206)
	(generator "pcbnew")
	(generator_version "10.0")
	(general
		(thickness 1.6)
		(legacy_teardrops no)
	)
	(paper "A4")
	(title_block
		(title "01162023_DA0F0TEBIF0_F0T_Expander_BD_F_brd_V02_OCP.brd")
		(comment 1 "Grand Teton / footprints 4607-4613 of 9728")
	)
	(layers
		(0 "F.Cu" signal "TOP")
		(4 "In1.Cu" signal "GND")
		(6 "In2.Cu" signal "VCC")
		(8 "In3.Cu" signal "VCC1")
		(10 "In4.Cu" signal "GND1")
		(12 "In5.Cu" signal "IN1")
		(14 "In6.Cu" signal "GND2")
		(16 "In7.Cu" signal "IN2")
		(18 "In8.Cu" signal "GND3")
		(20 "In9.Cu" signal "IN3")
		(22 "In10.Cu" signal "GND4")
		(24 "In11.Cu" signal "IN4")
		(26 "In12.Cu" signal "GND5")
		(28 "In13.Cu" signal "IN5")
		(30 "In14.Cu" signal "GND6")
		(32 "In15.Cu" signal "IN6")
		(34 "In16.Cu" signal "GND7")
		(2 "B.Cu" signal "BOTTOM")
		(9 "F.Adhes" user "F.Adhesive")
		(11 "B.Adhes" user "B.Adhesive")
		(13 "F.Paste" user "Package Geometry/Pastemask Top")
		(15 "B.Paste" user "Package Geometry/Pastemask Bottom")
		(5 "F.SilkS" user "Ref Des/Silkscreen Top")
		(7 "B.SilkS" user "Ref Des/Silkscreen Bottom")
		(1 "F.Mask" user "Board Geometry/Soldermask Top")
		(3 "B.Mask" user "Board Geometry/Soldermask Bottom")
		(17 "Dwgs.User" user "User.Drawings")
		(19 "Cmts.User" user "User.Comments")
		(21 "Eco1.User" user "User.Eco1")
		(23 "Eco2.User" user "User.Eco2")
		(25 "Edge.Cuts" user "Board Geometry/Outline")
		(27 "Margin" user)
		(31 "F.CrtYd" user "Package Geometry/Place Bound Top")
		(29 "B.CrtYd" user "Package Geometry/Place Bound Bottom")
		(35 "F.Fab" user "Ref Des/Assembly Top")
		(33 "B.Fab" user "Ref Des/Assembly Bottom")
	)
	(footprint ""
		(layer "F.Cu")
		(at 400.543776 -42.84091)
		(property "Reference" "R648"
			(at 0 0 0)
			(layer "F.SilkS")
			(hide yes)
			(effects
				(font
					(size 1.27 1.27)
				)
			)
		)
		(property "Value" ""
			(at 0 0 0)
			(layer "F.Fab")
			(effects
				(font
					(size 1.27 1.27)
				)
			)
		)
		(duplicate_pad_numbers_are_jumpers no)
		(fp_line
			(start -0.7874 -0.4064)
			(end 0.7874 -0.4064)
			(stroke
				(width 0.1524)
				(type default)
			)
			(layer "F.SilkS")
		)
		(fp_line
			(start -0.7874 0.4064)
			(end -0.7874 -0.4064)
			(stroke
				(width 0.1524)
				(type default)
			)
			(layer "F.SilkS")
		)
		(fp_line
			(start 0.7874 -0.4064)
			(end 0.7874 0.4064)
			(stroke
				(width 0.1524)
				(type default)
			)
			(layer "F.SilkS")
		)
		(fp_line
			(start 0.7874 0.4064)
			(end -0.7874 0.4064)
			(stroke
				(width 0.1524)
				(type default)
			)
			(layer "F.SilkS")
		)
		(fp_line
			(start -0.67945 -0.305054)
			(end -0.12065 -0.305054)
			(stroke
				(width 0.1)
				(type default)
			)
			(layer "F.Fab")
		)
		(fp_line
			(start -0.67945 0.3048)
			(end -0.67945 -0.305054)
			(stroke
				(width 0.1)
				(type default)
			)
			(layer "F.Fab")
		)
		(fp_line
			(start -0.12065 -0.305054)
			(end -0.12065 -0.2794)
			(stroke
				(width 0.1)
				(type default)
			)
			(layer "F.Fab")
		)
		(fp_line
			(start -0.12065 -0.2794)
			(end 0.12065 -0.2794)
			(stroke
				(width 0.1)
				(type default)
			)
			(layer "F.Fab")
		)
		(fp_line
			(start -0.12065 0.2794)
			(end -0.12065 0.3048)
			(stroke
				(width 0.1)
				(type default)
			)
			(layer "F.Fab")
		)
		(fp_line
			(start -0.12065 0.3048)
			(end -0.67945 0.3048)
			(stroke
				(width 0.1)
				(type default)
			)
			(layer "F.Fab")
		)
		(fp_line
			(start 0.120396 0.2794)
			(end -0.12065 0.2794)
			(stroke
				(width 0.1)
				(type default)
			)
			(layer "F.Fab")
		)
		(fp_line
			(start 0.120396 0.3048)
			(end 0.120396 0.2794)
			(stroke
				(width 0.1)
				(type default)
			)
			(layer "F.Fab")
		)
		(fp_line
			(start 0.12065 -0.3048)
			(end 0.67945 -0.3048)
			(stroke
				(width 0.1)
				(type default)
			)
			(layer "F.Fab")
		)
		(fp_line
			(start 0.12065 -0.2794)
			(end 0.12065 -0.3048)
			(stroke
				(width 0.1)
				(type default)
			)
			(layer "F.Fab")
		)
		(fp_line
			(start 0.67945 -0.3048)
			(end 0.67945 0.3048)
			(stroke
				(width 0.1)
				(type default)
			)
			(layer "F.Fab")
		)
		(fp_line
			(start 0.67945 0.3048)
			(end 0.120396 0.3048)
			(stroke
				(width 0.1)
				(type default)
			)
			(layer "F.Fab")
		)
		(pad "1" smd circle
			(at -0.40005 0)
			(size 0 0)
			(layers "F.Cu" "F.Mask" "F.Paste")
			(net "SSD13_ADC_A1")
		)
		(pad "2" smd circle
			(at 0.40005 0)
			(size 0 0)
			(layers "F.Cu" "F.Mask" "F.Paste")
			(net "P3V3_AUX")
		)
	)
	(footprint ""
		(layer "F.Cu")
		(at 5.888736 -37.795962 -90)
		(property "Reference" "PC674"
			(at 0 0 270)
			(layer "F.SilkS")
			(hide yes)
			(effects
				(font
					(size 1.27 1.27)
				)
			)
		)
		(property "Value" ""
			(at 0 0 270)
			(layer "F.Fab")
			(effects
				(font
					(size 1.27 1.27)
				)
			)
		)
		(duplicate_pad_numbers_are_jumpers no)
		(fp_line
			(start -0.7874 0.4064)
			(end -0.7874 -0.4064)
			(stroke
				(width 0.1524)
				(type default)
			)
			(layer "F.SilkS")
		)
		(fp_line
			(start 0.7874 0.4064)
			(end -0.7874 0.4064)
			(stroke
				(width 0.1524)
				(type default)
			)
			(layer "F.SilkS")
		)
		(fp_line
			(start -0.7874 -0.4064)
			(end 0.7874 -0.4064)
			(stroke
				(width 0.1524)
				(type default)
			)
			(layer "F.SilkS")
		)
		(fp_line
			(start 0.7874 -0.4064)
			(end 0.7874 0.4064)
			(stroke
				(width 0.1524)
				(type default)
			)
			(layer "F.SilkS")
		)
		(fp_line
			(start -0.67945 0.3048)
			(end -0.67945 -0.305054)
			(stroke
				(width 0.1)
				(type default)
			)
			(layer "F.Fab")
		)
		(fp_line
			(start -0.12065 0.3048)
			(end -0.67945 0.3048)
			(stroke
				(width 0.1)
				(type default)
			)
			(layer "F.Fab")
		)
		(fp_line
			(start 0.120396 0.3048)
			(end 0.120396 0.2794)
			(stroke
				(width 0.1)
				(type default)
			)
			(layer "F.Fab")
		)
		(fp_line
			(start 0.67945 0.3048)
			(end 0.120396 0.3048)
			(stroke
				(width 0.1)
				(type default)
			)
			(layer "F.Fab")
		)
		(fp_line
			(start -0.12065 0.2794)
			(end -0.12065 0.3048)
			(stroke
				(width 0.1)
				(type default)
			)
			(layer "F.Fab")
		)
		(fp_line
			(start 0.120396 0.2794)
			(end -0.12065 0.2794)
			(stroke
				(width 0.1)
				(type default)
			)
			(layer "F.Fab")
		)
		(fp_line
			(start -0.12065 -0.2794)
			(end 0.12065 -0.2794)
			(stroke
				(width 0.1)
				(type default)
			)
			(layer "F.Fab")
		)
		(fp_line
			(start 0.12065 -0.2794)
			(end 0.12065 -0.3048)
			(stroke
				(width 0.1)
				(type default)
			)
			(layer "F.Fab")
		)
		(fp_line
			(start 0.12065 -0.3048)
			(end 0.67945 -0.3048)
			(stroke
				(width 0.1)
				(type default)
			)
			(layer "F.Fab")
		)
		(fp_line
			(start 0.67945 -0.3048)
			(end 0.67945 0.3048)
			(stroke
				(width 0.1)
				(type default)
			)
			(layer "F.Fab")
		)
		(fp_line
			(start -0.67945 -0.305054)
			(end -0.12065 -0.305054)
			(stroke
				(width 0.1)
				(type default)
			)
			(layer "F.Fab")
		)
		(fp_line
			(start -0.12065 -0.305054)
			(end -0.12065 -0.2794)
			(stroke
				(width 0.1)
				(type default)
			)
			(layer "F.Fab")
		)
		(pad "1" smd circle
			(at -0.40005 0 270)
			(size 0 0)
			(layers "F.Cu" "F.Mask" "F.Paste")
			(net "P3V3_SSD0_CO_MODE")
		)
		(pad "2" smd circle
			(at 0.40005 0 270)
			(size 0 0)
			(layers "F.Cu" "F.Mask" "F.Paste")
			(net "GND")
		)
	)
	(footprint ""
		(layer "F.Cu")
		(at 153.104596 -141.87297 180)
		(property "Reference" "R133"
			(at 0 0 180)
			(layer "F.SilkS")
			(hide yes)
			(effects
				(font
					(size 1.27 1.27)
				)
			)
		)
		(property "Value" ""
			(at 0 0 180)
			(layer "F.Fab")
			(effects
				(font
					(size 1.27 1.27)
				)
			)
		)
		(duplicate_pad_numbers_are_jumpers no)
		(fp_line
			(start 0.7874 0.4064)
			(end -0.7874 0.4064)
			(stroke
				(width 0.1524)
				(type default)
			)
			(layer "F.SilkS")
		)
		(fp_line
			(start 0.7874 -0.4064)
			(end 0.7874 0.4064)
			(stroke
				(width 0.1524)
				(type default)
			)
			(layer "F.SilkS")
		)
		(fp_line
			(start -0.7874 0.4064)
			(end -0.7874 -0.4064)
			(stroke
				(width 0.1524)
				(type default)
			)
			(layer "F.SilkS")
		)
		(fp_line
			(start -0.7874 -0.4064)
			(end 0.7874 -0.4064)
			(stroke
				(width 0.1524)
				(type default)
			)
			(layer "F.SilkS")
		)
		(fp_line
			(start 0.67945 0.3048)
			(end 0.120396 0.3048)
			(stroke
				(width 0.1)
				(type default)
			)
			(layer "F.Fab")
		)
		(fp_line
			(start 0.67945 -0.3048)
			(end 0.67945 0.3048)
			(stroke
				(width 0.1)
				(type default)
			)
			(layer "F.Fab")
		)
		(fp_line
			(start 0.12065 -0.2794)
			(end 0.12065 -0.3048)
			(stroke
				(width 0.1)
				(type default)
			)
			(layer "F.Fab")
		)
		(fp_line
			(start 0.12065 -0.3048)
			(end 0.67945 -0.3048)
			(stroke
				(width 0.1)
				(type default)
			)
			(layer "F.Fab")
		)
		(fp_line
			(start 0.120396 0.3048)
			(end 0.120396 0.2794)
			(stroke
				(width 0.1)
				(type default)
			)
			(layer "F.Fab")
		)
		(fp_line
			(start 0.120396 0.2794)
			(end -0.12065 0.2794)
			(stroke
				(width 0.1)
				(type default)
			)
			(layer "F.Fab")
		)
		(fp_line
			(start -0.12065 0.3048)
			(end -0.67945 0.3048)
			(stroke
				(width 0.1)
				(type default)
			)
			(layer "F.Fab")
		)
		(fp_line
			(start -0.12065 0.2794)
			(end -0.12065 0.3048)
			(stroke
				(width 0.1)
				(type default)
			)
			(layer "F.Fab")
		)
		(fp_line
			(start -0.12065 -0.2794)
			(end 0.12065 -0.2794)
			(stroke
				(width 0.1)
				(type default)
			)
			(layer "F.Fab")
		)
		(fp_line
			(start -0.12065 -0.305054)
			(end -0.12065 -0.2794)
			(stroke
				(width 0.1)
				(type default)
			)
			(layer "F.Fab")
		)
		(fp_line
			(start -0.67945 0.3048)
			(end -0.67945 -0.305054)
			(stroke
				(width 0.1)
				(type default)
			)
			(layer "F.Fab")
		)
		(fp_line
			(start -0.67945 -0.305054)
			(end -0.12065 -0.305054)
			(stroke
				(width 0.1)
				(type default)
			)
			(layer "F.Fab")
		)
		(pad "1" smd circle
			(at -0.40005 0 180)
			(size 0 0)
			(layers "F.Cu" "F.Mask" "F.Paste")
			(net "NIC2_BIF1_N")
		)
		(pad "2" smd circle
			(at 0.40005 0 180)
			(size 0 0)
			(layers "F.Cu" "F.Mask" "F.Paste")
			(net "P3V3_AUX")
		)
	)
	(footprint ""
		(layer "F.Cu")
		(at 221.251272 -144.958562)
		(property "Reference" "R4207"
			(at 0 0 0)
			(layer "F.SilkS")
			(hide yes)
			(effects
				(font
					(size 1.27 1.27)
				)
			)
		)
		(property "Value" ""
			(at 0 0 0)
			(layer "F.Fab")
			(effects
				(font
					(size 1.27 1.27)
				)
			)
		)
		(duplicate_pad_numbers_are_jumpers no)
		(fp_line
			(start -0.7874 -0.4064)
			(end 0.7874 -0.4064)
			(stroke
				(width 0.1524)
				(type default)
			)
			(layer "F.SilkS")
		)
		(fp_line
			(start -0.7874 0.4064)
			(end -0.7874 -0.4064)
			(stroke
				(width 0.1524)
				(type default)
			)
			(layer "F.SilkS")
		)
		(fp_line
			(start 0.7874 -0.4064)
			(end 0.7874 0.4064)
			(stroke
				(width 0.1524)
				(type default)
			)
			(layer "F.SilkS")
		)
		(fp_line
			(start 0.7874 0.4064)
			(end -0.7874 0.4064)
			(stroke
				(width 0.1524)
				(type default)
			)
			(layer "F.SilkS")
		)
		(fp_line
			(start -0.67945 -0.305054)
			(end -0.12065 -0.305054)
			(stroke
				(width 0.1)
				(type default)
			)
			(layer "F.Fab")
		)
		(fp_line
			(start -0.67945 0.3048)
			(end -0.67945 -0.305054)
			(stroke
				(width 0.1)
				(type default)
			)
			(layer "F.Fab")
		)
		(fp_line
			(start -0.12065 -0.305054)
			(end -0.12065 -0.2794)
			(stroke
				(width 0.1)
				(type default)
			)
			(layer "F.Fab")
		)
		(fp_line
			(start -0.12065 -0.2794)
			(end 0.12065 -0.2794)
			(stroke
				(width 0.1)
				(type default)
			)
			(layer "F.Fab")
		)
		(fp_line
			(start -0.12065 0.2794)
			(end -0.12065 0.3048)
			(stroke
				(width 0.1)
				(type default)
			)
			(layer "F.Fab")
		)
		(fp_line
			(start -0.12065 0.3048)
			(end -0.67945 0.3048)
			(stroke
				(width 0.1)
				(type default)
			)
			(layer "F.Fab")
		)
		(fp_line
			(start 0.120396 0.2794)
			(end -0.12065 0.2794)
			(stroke
				(width 0.1)
				(type default)
			)
			(layer "F.Fab")
		)
		(fp_line
			(start 0.120396 0.3048)
			(end 0.120396 0.2794)
			(stroke
				(width 0.1)
				(type default)
			)
			(layer "F.Fab")
		)
		(fp_line
			(start 0.12065 -0.3048)
			(end 0.67945 -0.3048)
			(stroke
				(width 0.1)
				(type default)
			)
			(layer "F.Fab")
		)
		(fp_line
			(start 0.12065 -0.2794)
			(end 0.12065 -0.3048)
			(stroke
				(width 0.1)
				(type default)
			)
			(layer "F.Fab")
		)
		(fp_line
			(start 0.67945 -0.3048)
			(end 0.67945 0.3048)
			(stroke
				(width 0.1)
				(type default)
			)
			(layer "F.Fab")
		)
		(fp_line
			(start 0.67945 0.3048)
			(end 0.120396 0.3048)
			(stroke
				(width 0.1)
				(type default)
			)
			(layer "F.Fab")
		)
		(pad "1" smd circle
			(at -0.40005 0)
			(size 0 0)
			(layers "F.Cu" "F.Mask" "F.Paste")
			(net "GND")
		)
		(pad "2" smd circle
			(at 0.40005 0)
			(size 0 0)
			(layers "F.Cu" "F.Mask" "F.Paste")
			(net "PD_CK440_PEX_SBI_DATA_IN")
		)
	)
	(footprint ""
		(layer "F.Cu")
		(at 312.982356 -29.875734)
		(property "Reference" "PU130"
			(at -3.328924 -2.221992 90)
			(unlocked yes)
			(layer "F.SilkS")
			(effects
				(font
					(size 0.7874 0.5842)
					(thickness 0.1524)
				)
			)
		)
		(property "Value" ""
			(at 0 0 0)
			(layer "F.Fab")
			(effects
				(font
					(size 1.27 1.27)
				)
			)
		)
		(duplicate_pad_numbers_are_jumpers no)
		(fp_line
			(start -1.239774 -1.495298)
			(end 1.239774 -1.495298)
			(stroke
				(width 0.1524)
				(type default)
			)
			(layer "F.SilkS")
		)
		(fp_line
			(start -1.239774 1.495298)
			(end -1.239774 -1.495298)
			(stroke
				(width 0.1524)
				(type default)
			)
			(layer "F.SilkS")
		)
		(fp_line
			(start 1.239774 -1.495298)
			(end 1.239774 1.495298)
			(stroke
				(width 0.1524)
				(type default)
			)
			(layer "F.SilkS")
		)
		(fp_line
			(start 1.239774 1.495298)
			(end -1.239774 1.495298)
			(stroke
				(width 0.1524)
				(type default)
			)
			(layer "F.SilkS")
		)
		(fp_poly
			(pts
				(xy -1.986788 -1.275842) (xy -2.705354 -0.557276) (xy -1.627632 -0.19812)
			)
			(stroke
				(width 0)
				(type default)
			)
			(fill yes)
			(layer "F.SilkS")
		)
		(fp_line
			(start -0.8001 -1.050036)
			(end 0.8001 -1.050036)
			(stroke
				(width 0.1)
				(type default)
			)
			(layer "F.Fab")
		)
		(fp_line
			(start -0.8001 1.050036)
			(end -0.8001 -1.050036)
			(stroke
				(width 0.1)
				(type default)
			)
			(layer "F.Fab")
		)
		(fp_line
			(start 0.8001 -1.050036)
			(end 0.8001 1.050036)
			(stroke
				(width 0.1)
				(type default)
			)
			(layer "F.Fab")
		)
		(fp_line
			(start 0.8001 1.050036)
			(end -0.8001 1.050036)
			(stroke
				(width 0.1)
				(type default)
			)
			(layer "F.Fab")
		)
		(fp_poly
			(pts
				(xy -2.458974 -0.508) (xy -2.458974 0.508) (xy -1.442974 0)
			)
			(stroke
				(width 0)
				(type default)
			)
			(fill yes)
			(layer "F.Fab")
		)
		(pad "1_2" smd circle
			(at -0.374904 0 90)
			(size 0 0)
			(layers "F.Cu" "F.Mask" "F.Paste")
			(net "P3V3_AUX")
		)
		(pad "3" smd rect
			(at -0.499872 0.999998)
			(size 0.254 0.7112)
			(layers "F.Cu" "F.Mask" "F.Paste")
			(net "GND")
		)
		(pad "4" smd rect
			(at 0 0.999998)
			(size 0.254 0.7112)
			(layers "F.Cu" "F.Mask" "F.Paste")
			(net "P3V3_SSD11_CO_ILIMIT")
		)
		(pad "5" smd rect
			(at 0.499872 0.999998)
			(size 0.254 0.7112)
			(layers "F.Cu" "F.Mask" "F.Paste")
			(net "P3V3_SSD11_CO_MODE")
		)
		(pad "6_7" smd circle
			(at 0.374904 0 270)
			(size 0 0)
			(layers "F.Cu" "F.Mask" "F.Paste")
			(net "P3V3_SSD11")
		)
		(pad "8" smd rect
			(at 0.499872 -0.999998)
			(size 0.254 0.7112)
			(layers "F.Cu" "F.Mask" "F.Paste")
			(net "P3V3_SSD11_CO_GATE")
		)
		(pad "9" smd rect
			(at 0 -0.999998)
			(size 0.254 0.7112)
			(layers "F.Cu" "F.Mask" "F.Paste")
			(net "P3V3_SSD11_CO_EN")
		)
		(pad "10" smd rect
			(at -0.499872 -0.999998)
			(size 0.254 0.7112)
			(layers "F.Cu" "F.Mask" "F.Paste")
			(net "P3V3_SSD11_CO_DV_DT")
		)
	)
	(footprint ""
		(layer "F.Cu")
		(at 280.307542 -356.244906 90)
		(property "Reference" "C2353"
			(at 0 0 90)
			(layer "F.SilkS")
			(hide yes)
			(effects
				(font
					(size 1.27 1.27)
				)
			)
		)
		(property "Value" ""
			(at 0 0 90)
			(layer "F.Fab")
			(effects
				(font
					(size 1.27 1.27)
				)
			)
		)
		(duplicate_pad_numbers_are_jumpers no)
		(fp_line
			(start 0.299974 -0.150114)
			(end 0.299974 0.150114)
			(stroke
				(width 0.1)
				(type default)
			)
			(layer "F.Fab")
		)
		(fp_line
			(start -0.299974 -0.150114)
			(end 0.299974 -0.150114)
			(stroke
				(width 0.1)
				(type default)
			)
			(layer "F.Fab")
		)
		(fp_line
			(start 0.299974 0.150114)
			(end -0.299974 0.150114)
			(stroke
				(width 0.1)
				(type default)
			)
			(layer "F.Fab")
		)
		(fp_line
			(start -0.299974 0.150114)
			(end -0.299974 -0.150114)
			(stroke
				(width 0.1)
				(type default)
			)
			(layer "F.Fab")
		)
		(pad "1" smd rect
			(at -0.2667 0 90)
			(size 0.3048 0.381)
			(layers "F.Cu" "F.Mask" "F.Paste")
			(net "P5E_PEX2_STN4_TX_DP<73>")
		)
		(pad "2" smd rect
			(at 0.2667 0 90)
			(size 0.3048 0.381)
			(layers "F.Cu" "F.Mask" "F.Paste")
			(net "P5E_PEX2_STN4_TX_C_DP<73>")
		)
	)
	(footprint ""
		(layer "F.Cu")
		(at 243.476018 -236.682026 -90)
		(property "Reference" "R6241"
			(at 0 0 270)
			(layer "F.SilkS")
			(hide yes)
			(effects
				(font
					(size 1.27 1.27)
				)
			)
		)
		(property "Value" ""
			(at 0 0 270)
			(layer "F.Fab")
			(effects
				(font
					(size 1.27 1.27)
				)
			)
		)
		(duplicate_pad_numbers_are_jumpers no)
		(fp_line
			(start -0.7874 0.4064)
			(end -0.7874 -0.4064)
			(stroke
				(width 0.1524)
				(type default)
			)
			(layer "F.SilkS")
		)
		(fp_line
			(start 0.7874 0.4064)
			(end -0.7874 0.4064)
			(stroke
				(width 0.1524)
				(type default)
			)
			(layer "F.SilkS")
		)
		(fp_line
			(start -0.7874 -0.4064)
			(end 0.7874 -0.4064)
			(stroke
				(width 0.1524)
				(type default)
			)
			(layer "F.SilkS")
		)
		(fp_line
			(start 0.7874 -0.4064)
			(end 0.7874 0.4064)
			(stroke
				(width 0.1524)
				(type default)
			)
			(layer "F.SilkS")
		)
		(fp_line
			(start -0.67945 0.3048)
			(end -0.67945 -0.305054)
			(stroke
				(width 0.1)
				(type default)
			)
			(layer "F.Fab")
		)
		(fp_line
			(start -0.12065 0.3048)
			(end -0.67945 0.3048)
			(stroke
				(width 0.1)
				(type default)
			)
			(layer "F.Fab")
		)
		(fp_line
			(start 0.120396 0.3048)
			(end 0.120396 0.2794)
			(stroke
				(width 0.1)
				(type default)
			)
			(layer "F.Fab")
		)
		(fp_line
			(start 0.67945 0.3048)
			(end 0.120396 0.3048)
			(stroke
				(width 0.1)
				(type default)
			)
			(layer "F.Fab")
		)
		(fp_line
			(start -0.12065 0.2794)
			(end -0.12065 0.3048)
			(stroke
				(width 0.1)
				(type default)
			)
			(layer "F.Fab")
		)
		(fp_line
			(start 0.120396 0.2794)
			(end -0.12065 0.2794)
			(stroke
				(width 0.1)
				(type default)
			)
			(layer "F.Fab")
		)
		(fp_line
			(start -0.12065 -0.2794)
			(end 0.12065 -0.2794)
			(stroke
				(width 0.1)
				(type default)
			)
			(layer "F.Fab")
		)
		(fp_line
			(start 0.12065 -0.2794)
			(end 0.12065 -0.3048)
			(stroke
				(width 0.1)
				(type default)
			)
			(layer "F.Fab")
		)
		(fp_line
			(start 0.12065 -0.3048)
			(end 0.67945 -0.3048)
			(stroke
				(width 0.1)
				(type default)
			)
			(layer "F.Fab")
		)
		(fp_line
			(start 0.67945 -0.3048)
			(end 0.67945 0.3048)
			(stroke
				(width 0.1)
				(type default)
			)
			(layer "F.Fab")
		)
		(fp_line
			(start -0.67945 -0.305054)
			(end -0.12065 -0.305054)
			(stroke
				(width 0.1)
				(type default)
			)
			(layer "F.Fab")
		)
		(fp_line
			(start -0.12065 -0.305054)
			(end -0.12065 -0.2794)
			(stroke
				(width 0.1)
				(type default)
			)
			(layer "F.Fab")
		)
		(pad "1" smd circle
			(at -0.40005 0 270)
			(size 0 0)
			(layers "F.Cu" "F.Mask" "F.Paste")
			(net "SMB_BIC_RECOVER_IOEXP_SCL")
		)
		(pad "2" smd circle
			(at 0.40005 0 270)
			(size 0 0)
			(layers "F.Cu" "F.Mask" "F.Paste")
			(net "SMB_MB_R_SCL")
		)
	)
)
